FILE_TYPE = CONNECTIVITY;
{Allegro Design Entry HDL 17.4-2019 S026 (4007227) 1/17/2022}
"PAGE_NUMBER" = 362;
0"NC";
END.
